(kicad_pcb
	(version 20260206)
	(generator "pcbnew")
	(generator_version "10.0")
	(general
		(thickness 1.6)
		(legacy_teardrops no)
	)
	(paper "A4")
	(title_block
		(title "netronome-mezz — pcbd0082-001_rev01_jul9_a.brd")
		(comment 1 "Open CloudServer (Microsoft) / footprints 542-550 of 714")
	)
	(layers
		(0 "F.Cu" signal "TOP")
		(4 "In1.Cu" signal "02_GND")
		(6 "In2.Cu" signal "03_SIG")
		(8 "In3.Cu" signal "04_SIG")
		(10 "In4.Cu" signal "05_GND")
		(12 "In5.Cu" signal "06_PWR1")
		(14 "In6.Cu" signal "07_SIG")
		(16 "In7.Cu" signal "08_SIG")
		(18 "In8.Cu" signal "09_GND")
		(2 "B.Cu" signal "BOTTOM")
		(9 "F.Adhes" user "F.Adhesive")
		(11 "B.Adhes" user "B.Adhesive")
		(13 "F.Paste" user "Package Geometry/Pastemask Top")
		(15 "B.Paste" user "Package Geometry/Pastemask Bottom")
		(5 "F.SilkS" user "Ref Des/Silkscreen Top")
		(7 "B.SilkS" user "Ref Des/Silkscreen Bottom")
		(1 "F.Mask" user "Board Geometry/Soldermask Top")
		(3 "B.Mask" user "Board Geometry/Soldermask Bottom")
		(17 "Dwgs.User" user "User.Drawings")
		(19 "Cmts.User" user "User.Comments")
		(21 "Eco1.User" user "User.Eco1")
		(23 "Eco2.User" user "User.Eco2")
		(25 "Edge.Cuts" user "Board Geometry/Outline")
		(27 "Margin" user)
		(31 "F.CrtYd" user "Package Geometry/Place Bound Top")
		(29 "B.CrtYd" user "Package Geometry/Place Bound Bottom")
		(35 "F.Fab" user "Ref Des/Assembly Top")
		(33 "B.Fab" user "Ref Des/Assembly Bottom")
		(45 "User.4" user "COMPVAL_TYPE_BOTTOM")
	)
	(footprint ""
		(layer "B.Cu")
		(at 34.29762 23.622 -90)
		(property "Reference" "R50"
			(at 0 0 90)
			(layer "B.SilkS")
			(hide yes)
			(effects
				(font
					(size 1.27 1.27)
				)
				(justify mirror)
			)
		)
		(property "Value" "4.75K"
			(at 0.148158 1.3462 180)
			(unlocked yes)
			(layer "B.Fab")
			(hide yes)
			(effects
				(font
					(size 1.27 0.9652)
					(thickness 0.000001)
				)
				(justify left mirror)
			)
		)
		(property "Device Type" "REST4024"
			(at 0.148158 1.3462 180)
			(unlocked yes)
			(layer "B.Fab")
			(hide yes)
			(effects
				(font
					(size 1.27 0.9652)
					(thickness 0.000001)
				)
				(justify left mirror)
			)
		)
		(duplicate_pad_numbers_are_jumpers no)
		(fp_poly
			(pts
				(xy -0.635 1.0668) (xy -0.635 -1.0668) (xy 0.635 -1.0668) (xy 0.635 1.0668)
			)
			(stroke
				(width 0)
				(type default)
			)
			(fill no)
			(layer "B.CrtYd")
		)
		(fp_line
			(start -0.254 0.508)
			(end 0.254 0.508)
			(stroke
				(width 0.0254)
				(type default)
			)
			(layer "B.Fab")
		)
		(fp_line
			(start 0.254 0.508)
			(end 0.254 -0.508)
			(stroke
				(width 0.0254)
				(type default)
			)
			(layer "B.Fab")
		)
		(fp_line
			(start -0.254 -0.508)
			(end -0.254 0.508)
			(stroke
				(width 0.0254)
				(type default)
			)
			(layer "B.Fab")
		)
		(fp_line
			(start 0.254 -0.508)
			(end -0.254 -0.508)
			(stroke
				(width 0.0254)
				(type default)
			)
			(layer "B.Fab")
		)
		(pad "1" smd rect
			(at 0 -0.4191 90)
			(size 0.508 0.5334)
			(layers "B.Cu" "B.Mask" "B.Paste")
			(net "EXT_3.3V")
		)
		(pad "2" smd rect
			(at 0 0.4191 90)
			(size 0.508 0.5334)
			(layers "B.Cu" "B.Mask" "B.Paste")
			(net "CPLD_VERSION_0")
		)
		(zone
			(layer "B.Cu")
			(hatch none 0.5)
			(connect_pads
				(clearance 0)
			)
			(min_thickness 0.25)
			(keepout
				(tracks not_allowed)
				(vias allowed)
				(pads allowed)
				(copperpour not_allowed)
				(footprints allowed)
			)
			(placement
				(enabled no)
				(sheetname "")
			)
			(fill
				(thermal_gap 0.5)
				(thermal_bridge_width 0.5)
				(island_removal_mode 0)
			)
			(polygon
				(pts
					(xy 34.32302 23.5966) (xy 34.27222 23.5966) (xy 34.27222 23.6474) (xy 34.32302 23.6474)
				)
			)
		)
	)
	(footprint ""
		(layer "B.Cu")
		(at 22.479 4.953 90)
		(property "Reference" "R379"
			(at 0.60833 -1.143 0)
			(unlocked yes)
			(layer "B.SilkS")
			(effects
				(font
					(size 0.7874 0.5842)
					(thickness 0.127)
				)
				(justify left mirror)
			)
		)
		(property "Value" "4.75K"
			(at 0.148158 1.3462 0)
			(unlocked yes)
			(layer "B.Fab")
			(hide yes)
			(effects
				(font
					(size 1.27 0.9652)
					(thickness 0.000001)
				)
				(justify left mirror)
			)
		)
		(property "Device Type" "REST4024"
			(at 0.148158 1.3462 0)
			(unlocked yes)
			(layer "B.Fab")
			(hide yes)
			(effects
				(font
					(size 1.27 0.9652)
					(thickness 0.000001)
				)
				(justify left mirror)
			)
		)
		(duplicate_pad_numbers_are_jumpers no)
		(fp_poly
			(pts
				(xy -0.635 1.0668) (xy -0.635 -1.0668) (xy 0.635 -1.0668) (xy 0.635 1.0668)
			)
			(stroke
				(width 0)
				(type default)
			)
			(fill no)
			(layer "B.CrtYd")
		)
		(fp_line
			(start 0.254 -0.508)
			(end -0.254 -0.508)
			(stroke
				(width 0.0254)
				(type default)
			)
			(layer "B.Fab")
		)
		(fp_line
			(start -0.254 -0.508)
			(end -0.254 0.508)
			(stroke
				(width 0.0254)
				(type default)
			)
			(layer "B.Fab")
		)
		(fp_line
			(start 0.254 0.508)
			(end 0.254 -0.508)
			(stroke
				(width 0.0254)
				(type default)
			)
			(layer "B.Fab")
		)
		(fp_line
			(start -0.254 0.508)
			(end 0.254 0.508)
			(stroke
				(width 0.0254)
				(type default)
			)
			(layer "B.Fab")
		)
		(pad "1" smd rect
			(at 0 -0.4191 270)
			(size 0.508 0.5334)
			(layers "B.Cu" "B.Mask" "B.Paste")
			(net "NFP_SMBUS_ALERT_L")
		)
		(pad "2" smd rect
			(at 0 0.4191 270)
			(size 0.508 0.5334)
			(layers "B.Cu" "B.Mask" "B.Paste")
			(net "EXT_3.3V")
		)
		(zone
			(layer "B.Cu")
			(hatch none 0.5)
			(connect_pads
				(clearance 0)
			)
			(min_thickness 0.25)
			(keepout
				(tracks not_allowed)
				(vias allowed)
				(pads allowed)
				(copperpour not_allowed)
				(footprints allowed)
			)
			(placement
				(enabled no)
				(sheetname "")
			)
			(fill
				(thermal_gap 0.5)
				(thermal_bridge_width 0.5)
				(island_removal_mode 0)
			)
			(polygon
				(pts
					(xy 22.4536 4.9784) (xy 22.5044 4.9784) (xy 22.5044 4.9276) (xy 22.4536 4.9276)
				)
			)
		)
	)
	(footprint ""
		(layer "B.Cu")
		(at 61.236987 10.542016 180)
		(property "Reference" "C187"
			(at 0 0 0)
			(layer "B.SilkS")
			(hide yes)
			(effects
				(font
					(size 1.27 1.27)
				)
				(justify mirror)
			)
		)
		(property "Value" ""
			(at 0 0 0)
			(layer "B.Fab")
			(effects
				(font
					(size 1.27 1.27)
				)
				(justify mirror)
			)
		)
		(duplicate_pad_numbers_are_jumpers no)
		(fp_circle
			(center 0 0)
			(end -0.104648 0)
			(stroke
				(width 0.1016)
				(type default)
			)
			(fill no)
			(layer "B.SilkS")
		)
		(fp_poly
			(pts
				(xy 0.381 -0.889) (xy 0.381 0.889) (xy -0.381 0.889) (xy -0.381 -0.889)
			)
			(stroke
				(width 0)
				(type default)
			)
			(fill no)
			(layer "B.CrtYd")
		)
		(fp_line
			(start 0.508 1.016)
			(end 0.508 -1.016)
			(stroke
				(width 0.0254)
				(type default)
			)
			(layer "B.Fab")
		)
		(fp_line
			(start 0.508 -1.016)
			(end 0.254 -1.016)
			(stroke
				(width 0.0254)
				(type default)
			)
			(layer "B.Fab")
		)
		(fp_line
			(start 0.254 -1.016)
			(end -0.508 -1.016)
			(stroke
				(width 0.0254)
				(type default)
			)
			(layer "B.Fab")
		)
		(fp_line
			(start -0.508 1.016)
			(end 0.508 1.016)
			(stroke
				(width 0.0254)
				(type default)
			)
			(layer "B.Fab")
		)
		(fp_line
			(start -0.508 -1.016)
			(end -0.508 1.016)
			(stroke
				(width 0.0254)
				(type default)
			)
			(layer "B.Fab")
		)
		(pad "1" smd custom
			(at 0 -0.500126)
			(size 0.127 0.127)
			(layers "B.Cu" "B.Mask" "B.Paste")
			(net "VDDA_DDR0_32A")
			(options
				(clearance outline)
				(anchor circle)
			)
			(primitives
				(gr_poly
					(pts
						(xy -0.1778 0.254) (xy 0.1778 0.254) (xy 0.254 0.1778) (xy 0.254 -0.1778) (xy 0.1778 -0.254) (xy -0.1778 -0.254)
						(xy -0.254 -0.1778) (xy -0.254 0.1778)
					)
					(width 0)
					(fill yes)
				)
			)
		)
		(pad "2" smd custom
			(at 0 0.500126)
			(size 0.127 0.127)
			(layers "B.Cu" "B.Mask" "B.Paste")
			(net "GND")
			(options
				(clearance outline)
				(anchor circle)
			)
			(primitives
				(gr_poly
					(pts
						(xy -0.1778 0.254) (xy 0.1778 0.254) (xy 0.254 0.1778) (xy 0.254 -0.1778) (xy 0.1778 -0.254) (xy -0.1778 -0.254)
						(xy -0.254 -0.1778) (xy -0.254 0.1778)
					)
					(width 0)
					(fill yes)
				)
			)
		)
	)
	(footprint ""
		(layer "B.Cu")
		(at 81.850992 1.899006)
		(property "Reference" "V1_A-A03"
			(at 0 0 0)
			(layer "B.SilkS")
			(hide yes)
			(effects
				(font
					(size 1.27 1.27)
				)
				(justify mirror)
			)
		)
		(property "Value" ""
			(at 0 0 0)
			(layer "B.Fab")
			(effects
				(font
					(size 1.27 1.27)
				)
				(justify mirror)
			)
		)
		(duplicate_pad_numbers_are_jumpers no)
		(pad "1" thru_hole circle
			(at 0 0 180)
			(size 0.4572 0.4572)
			(drill 0.20574)
			(layers "*.Cu" "*.Mask")
			(remove_unused_layers no)
			(net "DDR0_32A_A3")
			(clearance 0.1143)
			(thermal_gap 0.1143)
		)
	)
	(footprint ""
		(layer "B.Cu")
		(at 63.736982 22.041993 90)
		(property "Reference" "R310"
			(at -0.844677 0.652018 0)
			(unlocked yes)
			(layer "B.SilkS")
			(effects
				(font
					(size 0.7874 0.5842)
					(thickness 0.127)
				)
				(justify mirror)
			)
		)
		(property "Value" ""
			(at 0 0 90)
			(layer "B.Fab")
			(effects
				(font
					(size 1.27 1.27)
				)
				(justify mirror)
			)
		)
		(duplicate_pad_numbers_are_jumpers no)
		(fp_circle
			(center 0 0)
			(end 0 0.104648)
			(stroke
				(width 0.1016)
				(type default)
			)
			(fill no)
			(layer "B.SilkS")
		)
		(fp_poly
			(pts
				(xy 0.381 -0.889) (xy 0.381 0.889) (xy -0.381 0.889) (xy -0.381 -0.889)
			)
			(stroke
				(width 0)
				(type default)
			)
			(fill no)
			(layer "B.CrtYd")
		)
		(fp_line
			(start 0.508 -1.016)
			(end 0.254 -1.016)
			(stroke
				(width 0.0254)
				(type default)
			)
			(layer "B.Fab")
		)
		(fp_line
			(start 0.254 -1.016)
			(end -0.508 -1.016)
			(stroke
				(width 0.0254)
				(type default)
			)
			(layer "B.Fab")
		)
		(fp_line
			(start -0.508 -1.016)
			(end -0.508 1.016)
			(stroke
				(width 0.0254)
				(type default)
			)
			(layer "B.Fab")
		)
		(fp_line
			(start 0.508 1.016)
			(end 0.508 -1.016)
			(stroke
				(width 0.0254)
				(type default)
			)
			(layer "B.Fab")
		)
		(fp_line
			(start -0.508 1.016)
			(end 0.508 1.016)
			(stroke
				(width 0.0254)
				(type default)
			)
			(layer "B.Fab")
		)
		(pad "1" smd custom
			(at 0 -0.500126 270)
			(size 0.127 0.127)
			(layers "B.Cu" "B.Mask" "B.Paste")
			(net "6N3963")
			(options
				(clearance outline)
				(anchor circle)
			)
			(primitives
				(gr_poly
					(pts
						(xy -0.1778 0.254) (xy 0.1778 0.254) (xy 0.254 0.1778) (xy 0.254 -0.1778) (xy 0.1778 -0.254) (xy -0.1778 -0.254)
						(xy -0.254 -0.1778) (xy -0.254 0.1778)
					)
					(width 0)
					(fill yes)
				)
			)
		)
		(pad "2" smd custom
			(at 0 0.500126 270)
			(size 0.127 0.127)
			(layers "B.Cu" "B.Mask" "B.Paste")
			(net "DDR_VDDQ")
			(options
				(clearance outline)
				(anchor circle)
			)
			(primitives
				(gr_poly
					(pts
						(xy -0.1778 0.254) (xy 0.1778 0.254) (xy 0.254 0.1778) (xy 0.254 -0.1778) (xy 0.1778 -0.254) (xy -0.1778 -0.254)
						(xy -0.254 -0.1778) (xy -0.254 0.1778)
					)
					(width 0)
					(fill yes)
				)
			)
		)
	)
	(footprint ""
		(layer "B.Cu")
		(at 82.65099 2.699004)
		(property "Reference" "V1_A-A02"
			(at 0 0 0)
			(layer "B.SilkS")
			(hide yes)
			(effects
				(font
					(size 1.27 1.27)
				)
				(justify mirror)
			)
		)
		(property "Value" ""
			(at 0 0 0)
			(layer "B.Fab")
			(effects
				(font
					(size 1.27 1.27)
				)
				(justify mirror)
			)
		)
		(duplicate_pad_numbers_are_jumpers no)
		(pad "1" thru_hole circle
			(at 0 0 180)
			(size 0.4572 0.4572)
			(drill 0.20574)
			(layers "*.Cu" "*.Mask")
			(remove_unused_layers no)
			(net "DDR0_32A_A2")
			(clearance 0.1143)
			(thermal_gap 0.1143)
		)
	)
	(footprint ""
		(layer "B.Cu")
		(at 60.728987 18.542 -90)
		(property "Reference" "C1"
			(at 0.15367 1.419987 0)
			(unlocked yes)
			(layer "B.SilkS")
			(effects
				(font
					(size 0.7874 0.5842)
					(thickness 0.127)
				)
				(justify left mirror)
			)
		)
		(property "Value" "22UF"
			(at 0.148158 1.7526 180)
			(unlocked yes)
			(layer "B.Fab")
			(hide yes)
			(effects
				(font
					(size 1.27 0.9652)
					(thickness 0.000001)
				)
				(justify left mirror)
			)
		)
		(property "Device Type" "CAPC0063"
			(at 0.148158 1.7526 180)
			(unlocked yes)
			(layer "B.Fab")
			(hide yes)
			(effects
				(font
					(size 1.27 0.9652)
					(thickness 0.000001)
				)
				(justify left mirror)
			)
		)
		(duplicate_pad_numbers_are_jumpers no)
		(fp_circle
			(center 0 0)
			(end 0 -0.127)
			(stroke
				(width 0.2032)
				(type default)
			)
			(fill no)
			(layer "B.SilkS")
		)
		(fp_poly
			(pts
				(xy -0.7874 -1.6637) (xy 0.7874 -1.6637) (xy 0.7874 1.6637) (xy -0.7874 1.6637)
			)
			(stroke
				(width 0)
				(type default)
			)
			(fill no)
			(layer "B.CrtYd")
		)
		(fp_line
			(start -0.4064 0.8128)
			(end 0.4064 0.8128)
			(stroke
				(width 0.0254)
				(type default)
			)
			(layer "B.Fab")
		)
		(fp_line
			(start 0.4064 0.8128)
			(end 0.4064 -0.7874)
			(stroke
				(width 0.0254)
				(type default)
			)
			(layer "B.Fab")
		)
		(fp_line
			(start -0.4064 -0.7874)
			(end -0.4064 0.8128)
			(stroke
				(width 0.0254)
				(type default)
			)
			(layer "B.Fab")
		)
		(fp_line
			(start 0.4064 -0.7874)
			(end -0.4064 -0.7874)
			(stroke
				(width 0.0254)
				(type default)
			)
			(layer "B.Fab")
		)
		(pad "1" smd rect
			(at 0 -0.8001 90)
			(size 0.8636 0.9652)
			(layers "B.Cu" "B.Mask" "B.Paste")
			(net "DDR_VDDQ")
		)
		(pad "2" smd rect
			(at 0 0.8001 90)
			(size 0.8636 0.9652)
			(layers "B.Cu" "B.Mask" "B.Paste")
			(net "GND")
		)
		(zone
			(layer "B.Cu")
			(hatch none 0.5)
			(connect_pads
				(clearance 0)
			)
			(min_thickness 0.25)
			(keepout
				(tracks not_allowed)
				(vias allowed)
				(pads allowed)
				(copperpour not_allowed)
				(footprints allowed)
			)
			(placement
				(enabled no)
				(sheetname "")
			)
			(fill
				(thermal_gap 0.5)
				(thermal_bridge_width 0.5)
				(island_removal_mode 0)
			)
			(polygon
				(pts
					(xy 60.982987 18.6055) (xy 60.982987 18.4785) (xy 60.474987 18.4785) (xy 60.474987 18.6055)
				)
			)
		)
	)
	(footprint ""
		(layer "B.Cu")
		(at 1.2319 11.176 90)
		(property "Reference" "R387"
			(at 0.22733 -0.9779 0)
			(unlocked yes)
			(layer "B.SilkS")
			(effects
				(font
					(size 0.7874 0.5842)
					(thickness 0.127)
				)
				(justify left mirror)
			)
		)
		(property "Value" "0"
			(at 0.148158 1.3462 0)
			(unlocked yes)
			(layer "B.Fab")
			(hide yes)
			(effects
				(font
					(size 1.27 0.9652)
					(thickness 0.000001)
				)
				(justify left mirror)
			)
		)
		(property "Device Type" "REST1111"
			(at 0.148158 1.3462 0)
			(unlocked yes)
			(layer "B.Fab")
			(hide yes)
			(effects
				(font
					(size 1.27 0.9652)
					(thickness 0.000001)
				)
				(justify left mirror)
			)
		)
		(duplicate_pad_numbers_are_jumpers no)
		(fp_poly
			(pts
				(xy -0.635 1.0668) (xy -0.635 -1.0668) (xy 0.635 -1.0668) (xy 0.635 1.0668)
			)
			(stroke
				(width 0)
				(type default)
			)
			(fill no)
			(layer "B.CrtYd")
		)
		(fp_line
			(start 0.254 -0.508)
			(end -0.254 -0.508)
			(stroke
				(width 0.0254)
				(type default)
			)
			(layer "B.Fab")
		)
		(fp_line
			(start -0.254 -0.508)
			(end -0.254 0.508)
			(stroke
				(width 0.0254)
				(type default)
			)
			(layer "B.Fab")
		)
		(fp_line
			(start 0.254 0.508)
			(end 0.254 -0.508)
			(stroke
				(width 0.0254)
				(type default)
			)
			(layer "B.Fab")
		)
		(fp_line
			(start -0.254 0.508)
			(end 0.254 0.508)
			(stroke
				(width 0.0254)
				(type default)
			)
			(layer "B.Fab")
		)
		(pad "1" smd rect
			(at 0 -0.4191 270)
			(size 0.508 0.5334)
			(layers "B.Cu" "B.Mask" "B.Paste")
			(net "NWK1_I2C_SCL")
		)
		(pad "2" smd rect
			(at 0 0.4191 270)
			(size 0.508 0.5334)
			(layers "B.Cu" "B.Mask" "B.Paste")
			(net "MUX_NFP_GPIO2_NWK1_I2C_SCL")
		)
		(zone
			(layer "B.Cu")
			(hatch none 0.5)
			(connect_pads
				(clearance 0)
			)
			(min_thickness 0.25)
			(keepout
				(tracks not_allowed)
				(vias allowed)
				(pads allowed)
				(copperpour not_allowed)
				(footprints allowed)
			)
			(placement
				(enabled no)
				(sheetname "")
			)
			(fill
				(thermal_gap 0.5)
				(thermal_bridge_width 0.5)
				(island_removal_mode 0)
			)
			(polygon
				(pts
					(xy 1.2065 11.2014) (xy 1.2573 11.2014) (xy 1.2573 11.1506) (xy 1.2065 11.1506)
				)
			)
		)
	)
	(footprint ""
		(layer "B.Cu")
		(at 63.236983 14.542008 180)
		(property "Reference" "R284"
			(at 0 0 0)
			(layer "B.SilkS")
			(hide yes)
			(effects
				(font
					(size 1.27 1.27)
				)
				(justify mirror)
			)
		)
		(property "Value" ""
			(at 0 0 0)
			(layer "B.Fab")
			(effects
				(font
					(size 1.27 1.27)
				)
				(justify mirror)
			)
		)
		(duplicate_pad_numbers_are_jumpers no)
		(fp_circle
			(center 0 0)
			(end -0.104648 0)
			(stroke
				(width 0.1016)
				(type default)
			)
			(fill no)
			(layer "B.SilkS")
		)
		(fp_poly
			(pts
				(xy 0.381 -0.889) (xy 0.381 0.889) (xy -0.381 0.889) (xy -0.381 -0.889)
			)
			(stroke
				(width 0)
				(type default)
			)
			(fill no)
			(layer "B.CrtYd")
		)
		(fp_line
			(start 0.508 1.016)
			(end 0.508 -1.016)
			(stroke
				(width 0.0254)
				(type default)
			)
			(layer "B.Fab")
		)
		(fp_line
			(start 0.508 -1.016)
			(end 0.254 -1.016)
			(stroke
				(width 0.0254)
				(type default)
			)
			(layer "B.Fab")
		)
		(fp_line
			(start 0.254 -1.016)
			(end -0.508 -1.016)
			(stroke
				(width 0.0254)
				(type default)
			)
			(layer "B.Fab")
		)
		(fp_line
			(start -0.508 1.016)
			(end 0.508 1.016)
			(stroke
				(width 0.0254)
				(type default)
			)
			(layer "B.Fab")
		)
		(fp_line
			(start -0.508 -1.016)
			(end -0.508 1.016)
			(stroke
				(width 0.0254)
				(type default)
			)
			(layer "B.Fab")
		)
		(pad "1" smd custom
			(at 0 -0.500126)
			(size 0.127 0.127)
			(layers "B.Cu" "B.Mask" "B.Paste")
			(net "DDR0_32A_VREF")
			(options
				(clearance outline)
				(anchor circle)
			)
			(primitives
				(gr_poly
					(pts
						(xy -0.1778 0.254) (xy 0.1778 0.254) (xy 0.254 0.1778) (xy 0.254 -0.1778) (xy 0.1778 -0.254) (xy -0.1778 -0.254)
						(xy -0.254 -0.1778) (xy -0.254 0.1778)
					)
					(width 0)
					(fill yes)
				)
			)
		)
		(pad "2" smd custom
			(at 0 0.500126)
			(size 0.127 0.127)
			(layers "B.Cu" "B.Mask" "B.Paste")
			(net "DDR_VDDQ")
			(options
				(clearance outline)
				(anchor circle)
			)
			(primitives
				(gr_poly
					(pts
						(xy -0.1778 0.254) (xy 0.1778 0.254) (xy 0.254 0.1778) (xy 0.254 -0.1778) (xy 0.1778 -0.254) (xy -0.1778 -0.254)
						(xy -0.254 -0.1778) (xy -0.254 0.1778)
					)
					(width 0)
					(fill yes)
				)
			)
		)
	)
)
